(kicad_pcb
	(version 20241229)
	(generator "pcbnew")
	(generator_version "9.0")
	(general
		(thickness 1.711)
		(legacy_teardrops no)
	)
	(paper "A4")
	(title_block
		(title "Antmicro Baseboard for Jetson AGX Thor")
		(date "2026-02-18")
		(rev "1.1.0")
		(company "Antmicro Ltd")
		(comment 1 "www.antmicro.com")
		(comment 9 "footprints 842-846 of 1170")
	)
	(layers
		(0 "F.Cu" signal)
		(4 "In1.Cu" signal)
		(6 "In2.Cu" signal)
		(8 "In3.Cu" signal)
		(10 "In4.Cu" jumper)
		(12 "In5.Cu" signal)
		(14 "In6.Cu" signal)
		(16 "In7.Cu" signal)
		(18 "In8.Cu" signal)
		(2 "B.Cu" signal)
		(9 "F.Adhes" user "F.Adhesive")
		(11 "B.Adhes" user "B.Adhesive")
		(13 "F.Paste" user)
		(15 "B.Paste" user)
		(5 "F.SilkS" user "F.Silkscreen")
		(7 "B.SilkS" user "B.Silkscreen")
		(1 "F.Mask" user)
		(3 "B.Mask" user)
		(17 "Dwgs.User" user "User.Drawings")
		(19 "Cmts.User" user "User.Comments")
		(21 "Eco1.User" user "User.Eco1")
		(23 "Eco2.User" user "User.Eco2")
		(25 "Edge.Cuts" user)
		(27 "Margin" user)
		(31 "F.CrtYd" user "F.Courtyard")
		(29 "B.CrtYd" user "B.Courtyard")
		(35 "F.Fab" user)
		(33 "B.Fab" user)
	)
	(footprint "antmicro-footprints:R_0402_1005Metric"
		(layer "B.Cu")
		(at 124.6 110.8)
		(descr "Resistor SMD 0402")
		(tags "resistor SMD 0402")
		(property "Reference" "R212"
			(at 3.9 -0.47 0)
			(layer "B.SilkS")
			(effects
				(font
					(size 0.7 0.7)
					(thickness 0.15)
				)
				(justify left top mirror)
			)
		)
		(property "Value" "R_0R_0402"
			(at -1.011843 -1.772046 0)
			(layer "B.Fab")
			(effects
				(font
					(size 0.7 0.7)
					(thickness 0.15)
				)
				(justify right top mirror)
			)
		)
		(property "Datasheet" "https://industrial.panasonic.com/cdbs/www-data/pdf/RDA0000/AOA0000C301.pdf"
			(at 0 0 0)
			(layer "B.Fab")
			(hide yes)
			(effects
				(font
					(size 1.27 1.27)
					(thickness 0.15)
				)
				(justify mirror)
			)
		)
		(property "Description" "SMD Chip Resistor, Jumper, 0 ohm, 100 mW, 0402 [1005 Metric], Thick Film, General Purpose"
			(at 0 0 0)
			(layer "B.Fab")
			(hide yes)
			(effects
				(font
					(size 1.27 1.27)
					(thickness 0.15)
				)
				(justify mirror)
			)
		)
		(property "MPN" "ERJ2GE0R00X"
			(at 0 0 180)
			(unlocked yes)
			(layer "B.Fab")
			(hide yes)
			(effects
				(font
					(size 1 1)
					(thickness 0.15)
				)
				(justify mirror)
			)
		)
		(property "Manufacturer" "Panasonic"
			(at 0 0 180)
			(unlocked yes)
			(layer "B.Fab")
			(hide yes)
			(effects
				(font
					(size 1 1)
					(thickness 0.15)
				)
				(justify mirror)
			)
		)
		(property "License" "Apache-2.0"
			(at 0 0 180)
			(unlocked yes)
			(layer "B.Fab")
			(hide yes)
			(effects
				(font
					(size 1 1)
					(thickness 0.15)
				)
				(justify mirror)
			)
		)
		(property "Val" "0R"
			(at 0 0 180)
			(unlocked yes)
			(layer "B.Fab")
			(hide yes)
			(effects
				(font
					(size 1 1)
					(thickness 0.15)
				)
				(justify mirror)
			)
		)
		(property "Tolerance" "~"
			(at 0 0 180)
			(unlocked yes)
			(layer "B.Fab")
			(hide yes)
			(effects
				(font
					(size 1 1)
					(thickness 0.15)
				)
				(justify mirror)
			)
		)
		(property "Current" "1A"
			(at 0 0 180)
			(unlocked yes)
			(layer "B.Fab")
			(hide yes)
			(effects
				(font
					(size 1 1)
					(thickness 0.15)
				)
				(justify mirror)
			)
		)
		(property "Author" "Antmicro"
			(at 0 0 180)
			(unlocked yes)
			(layer "B.Fab")
			(hide yes)
			(effects
				(font
					(size 1 1)
					(thickness 0.15)
				)
				(justify mirror)
			)
		)
		(property "Public" "False"
			(at 0 0 180)
			(unlocked yes)
			(layer "B.Fab")
			(hide yes)
			(effects
				(font
					(size 1 1)
					(thickness 0.15)
				)
				(justify mirror)
			)
		)
		(sheetname "/M.2/")
		(sheetfile "m2.kicad_sch")
		(attr smd)
		(fp_poly
			(pts
				(xy -0.925 0.47) (xy 0.925 0.47) (xy 0.925 -0.47) (xy -0.925 -0.47)
			)
			(stroke
				(width 0.05)
				(type default)
			)
			(fill no)
			(layer "B.CrtYd")
		)
		(fp_poly
			(pts
				(xy -0.5 0.25) (xy 0.5 0.25) (xy 0.5 -0.25) (xy -0.5 -0.25)
			)
			(stroke
				(width 0.15)
				(type solid)
			)
			(fill no)
			(layer "B.Fab")
		)
		(fp_text user "Author: Antmicro"
			(at -0.95 -4.169 0)
			(layer "B.Fab")
			(effects
				(font
					(size 0.7 0.7)
					(thickness 0.15)
				)
				(justify right top mirror)
			)
		)
		(fp_text user "License: Apache-2.0"
			(at -0.949999 -5.169 0)
			(layer "B.Fab")
			(effects
				(font
					(size 0.7 0.7)
					(thickness 0.15)
				)
				(justify right top mirror)
			)
		)
		(fp_text user "${REFERENCE}"
			(at -0.95 -3.168 0)
			(layer "B.Fab")
			(effects
				(font
					(size 0.7 0.7)
					(thickness 0.15)
				)
				(justify right top mirror)
			)
		)
		(pad "1" smd roundrect
			(at -0.48 0)
			(size 0.59 0.64)
			(layers "B.Cu" "B.Mask" "B.Paste")
			(roundrect_rratio 0.25)
			(net 224 "/M.2/M2_M_SUSCLK")
			(pintype "passive")
		)
		(pad "2" smd roundrect
			(at 0.48 0)
			(size 0.59 0.64)
			(layers "B.Cu" "B.Mask" "B.Paste")
			(roundrect_rratio 0.25)
			(net 1005 "/M.2/SUSCLK")
			(pintype "passive")
		)
	)
	(footprint "antmicro-footprints:SOT-23-5"
		(layer "B.Cu")
		(at 212.12 70.66 90)
		(property "Reference" "U32"
			(at 1.96 1.08 180)
			(layer "B.SilkS")
			(effects
				(font
					(size 0.7 0.7)
					(thickness 0.15)
				)
				(justify left bottom mirror)
			)
		)
		(property "Value" "NCP718BSN330T1G"
			(at 0.002 -2.799 270)
			(layer "B.Fab")
			(effects
				(font
					(size 0.7 0.7)
					(thickness 0.15)
				)
				(justify left bottom mirror)
			)
		)
		(property "Datasheet" "https://www.mouser.com/datasheet/2/308/NCP718_D-1224359.pdf"
			(at 0 0 270)
			(layer "B.Fab")
			(hide yes)
			(effects
				(font
					(size 1.27 1.27)
					(thickness 0.15)
				)
				(justify mirror)
			)
		)
		(property "Description" "Linear Voltage Regulator IC Positive Fixed 1 Output 300mA TSOT-23-5"
			(at 0 0 270)
			(layer "B.Fab")
			(hide yes)
			(effects
				(font
					(size 1.27 1.27)
					(thickness 0.15)
				)
				(justify mirror)
			)
		)
		(property "MPN" "NCP718BSN330T1G"
			(at 0 0 90)
			(unlocked yes)
			(layer "B.Fab")
			(hide yes)
			(effects
				(font
					(size 1 1)
					(thickness 0.15)
				)
				(justify mirror)
			)
		)
		(property "Manufacturer" "ON Semiconductor"
			(at 0 0 90)
			(unlocked yes)
			(layer "B.Fab")
			(hide yes)
			(effects
				(font
					(size 1 1)
					(thickness 0.15)
				)
				(justify mirror)
			)
		)
		(property "Author" "Antmicro"
			(at 0 0 90)
			(unlocked yes)
			(layer "B.Fab")
			(hide yes)
			(effects
				(font
					(size 1 1)
					(thickness 0.15)
				)
				(justify mirror)
			)
		)
		(property "License" "Apache-2.0"
			(at 0 0 90)
			(unlocked yes)
			(layer "B.Fab")
			(hide yes)
			(effects
				(font
					(size 1 1)
					(thickness 0.15)
				)
				(justify mirror)
			)
		)
		(sheetname "/USB Debug, PD/")
		(sheetfile "usb_debug_pd.kicad_sch")
		(attr smd)
		(fp_line
			(start -0.55 -1.6)
			(end -0.85 -1.6)
			(stroke
				(width 0.15)
				(type solid)
			)
			(layer "B.SilkS")
		)
		(fp_line
			(start -0.85 -1.6)
			(end -0.85 -1.301)
			(stroke
				(width 0.15)
				(type solid)
			)
			(layer "B.SilkS")
		)
		(fp_line
			(start 0.8 -1.599)
			(end 0.549 -1.599)
			(stroke
				(width 0.15)
				(type solid)
			)
			(layer "B.SilkS")
		)
		(fp_line
			(start 0.8 -1.3)
			(end 0.8 -1.599)
			(stroke
				(width 0.15)
				(type solid)
			)
			(layer "B.SilkS")
		)
		(fp_line
			(start 0.8 -0.55)
			(end 0.8 0.55)
			(stroke
				(width 0.15)
				(type solid)
			)
			(layer "B.SilkS")
		)
		(fp_line
			(start 0.8 1.3)
			(end 0.8 1.6)
			(stroke
				(width 0.15)
				(type solid)
			)
			(layer "B.SilkS")
		)
		(fp_line
			(start 0.8 1.6)
			(end 0.5 1.6)
			(stroke
				(width 0.15)
				(type solid)
			)
			(layer "B.SilkS")
		)
		(fp_line
			(start -0.8 1.6)
			(end -0.8 1.3)
			(stroke
				(width 0.15)
				(type solid)
			)
			(layer "B.SilkS")
		)
		(fp_line
			(start -0.8 1.6)
			(end -0.5 1.6)
			(stroke
				(width 0.15)
				(type solid)
			)
			(layer "B.SilkS")
		)
		(fp_circle
			(center -1.25 1.5)
			(end -1.2 1.5)
			(stroke
				(width 0.15)
				(type solid)
			)
			(fill yes)
			(layer "B.SilkS")
		)
		(fp_rect
			(start 1.9 1.76)
			(end -1.9 -1.75)
			(stroke
				(width 0.05)
				(type solid)
			)
			(fill no)
			(layer "B.CrtYd")
		)
		(fp_line
			(start -0.398 1.526)
			(end -0.874 1.05)
			(stroke
				(width 0.15)
				(type solid)
			)
			(layer "B.Fab")
		)
		(fp_rect
			(start 0.874 -1.523)
			(end -0.873 1.525)
			(stroke
				(width 0.15)
				(type solid)
			)
			(fill no)
			(layer "B.Fab")
		)
		(fp_text user "Author: Antmicro"
			(at -1.898 -5.499 270)
			(layer "B.Fab")
			(effects
				(font
					(size 0.7 0.7)
					(thickness 0.15)
				)
				(justify left bottom mirror)
			)
		)
		(fp_text user "License: Apache-2.0"
			(at -1.898 -6.7 270)
			(layer "B.Fab")
			(effects
				(font
					(size 0.7 0.7)
					(thickness 0.15)
				)
				(justify left bottom mirror)
			)
		)
		(fp_text user "${REFERENCE}"
			(at -1.898 -4.299 270)
			(layer "B.Fab")
			(effects
				(font
					(size 0.7 0.7)
					(thickness 0.15)
				)
				(justify left bottom mirror)
			)
		)
		(pad "1" smd rect
			(at -1.351 0.951 180)
			(size 0.55 1)
			(layers "B.Cu" "B.Mask" "B.Paste")
			(net 176 "/USB Debug, PD/USBC0_VBUS")
			(pinfunction "VIN")
			(pintype "passive")
		)
		(pad "2" smd rect
			(at -1.351 0 180)
			(size 0.55 1)
			(layers "B.Cu" "B.Mask" "B.Paste")
			(net 1 "GND")
			(pinfunction "GND")
			(pintype "passive")
		)
		(pad "3" smd rect
			(at -1.351 -0.949 180)
			(size 0.55 1)
			(layers "B.Cu" "B.Mask" "B.Paste")
			(net 176 "/USB Debug, PD/USBC0_VBUS")
			(pinfunction "EN")
			(pintype "passive")
		)
		(pad "4" smd rect
			(at 1.35 -0.949 180)
			(size 0.55 1)
			(layers "B.Cu" "B.Mask" "B.Paste")
			(net 1323 "unconnected-(U32-NC-Pad4)")
			(pinfunction "NC")
			(pintype "no_connect")
		)
		(pad "5" smd rect
			(at 1.35 0.951 180)
			(size 0.55 1)
			(layers "B.Cu" "B.Mask" "B.Paste")
			(net 334 "/USB Debug, PD/FTDI_3V3")
			(pinfunction "VOUT")
			(pintype "passive")
		)
	)
	(footprint "antmicro-footprints:R_0402_1005Metric"
		(layer "B.Cu")
		(at 130.11 151.2 -90)
		(descr "Resistor SMD 0402")
		(tags "resistor SMD 0402")
		(property "Reference" "R232"
			(at -1.1 -6.29 90)
			(layer "B.SilkS")
			(effects
				(font
					(size 0.7 0.7)
					(thickness 0.15)
				)
				(justify left bottom mirror)
			)
		)
		(property "Value" "R_10k_0402"
			(at -1.011843 -1.772047 90)
			(layer "B.Fab")
			(effects
				(font
					(size 0.7 0.7)
					(thickness 0.15)
				)
				(justify left bottom mirror)
			)
		)
		(property "Datasheet" "https://www.bourns.com/docs/product-datasheets/cr.pdf"
			(at 0 0 90)
			(layer "B.Fab")
			(hide yes)
			(effects
				(font
					(size 1.27 1.27)
					(thickness 0.15)
				)
				(justify mirror)
			)
		)
		(property "Description" "SMD Chip Resistor, 10 kohm, ± 1%, 62.5 mW, 0402 [1005 Metric], Thick Film, General Purpose"
			(at 0 0 90)
			(layer "B.Fab")
			(hide yes)
			(effects
				(font
					(size 1.27 1.27)
					(thickness 0.15)
				)
				(justify mirror)
			)
		)
		(property "MPN" "CR0402-FX-1002GLF"
			(at 0 0 90)
			(unlocked yes)
			(layer "B.Fab")
			(hide yes)
			(effects
				(font
					(size 1 1)
					(thickness 0.15)
				)
				(justify mirror)
			)
		)
		(property "Manufacturer" "Bourns"
			(at 0 0 90)
			(unlocked yes)
			(layer "B.Fab")
			(hide yes)
			(effects
				(font
					(size 1 1)
					(thickness 0.15)
				)
				(justify mirror)
			)
		)
		(property "License" "Apache-2.0"
			(at 0 0 90)
			(unlocked yes)
			(layer "B.Fab")
			(hide yes)
			(effects
				(font
					(size 1 1)
					(thickness 0.15)
				)
				(justify mirror)
			)
		)
		(property "Author" "Antmicro"
			(at 0 0 90)
			(unlocked yes)
			(layer "B.Fab")
			(hide yes)
			(effects
				(font
					(size 1 1)
					(thickness 0.15)
				)
				(justify mirror)
			)
		)
		(property "Val" "10k"
			(at 0 0 90)
			(unlocked yes)
			(layer "B.Fab")
			(hide yes)
			(effects
				(font
					(size 1 1)
					(thickness 0.15)
				)
				(justify mirror)
			)
		)
		(property "Tolerance" "1%"
			(at 0 0 90)
			(unlocked yes)
			(layer "B.Fab")
			(hide yes)
			(effects
				(font
					(size 1 1)
					(thickness 0.15)
				)
				(justify mirror)
			)
		)
		(sheetname "/Peripherals/")
		(sheetfile "peripherals.kicad_sch")
		(attr smd)
		(fp_rect
			(start -0.925 0.47)
			(end 0.925 -0.47)
			(stroke
				(width 0.05)
				(type default)
			)
			(fill no)
			(layer "B.CrtYd")
		)
		(fp_rect
			(start -0.5 0.25)
			(end 0.5 -0.25)
			(stroke
				(width 0.15)
				(type solid)
			)
			(fill no)
			(layer "B.Fab")
		)
		(fp_text user "License: Apache-2.0"
			(at -0.95 -5.169 90)
			(layer "B.Fab")
			(effects
				(font
					(size 0.7 0.7)
					(thickness 0.15)
				)
				(justify left bottom mirror)
			)
		)
		(fp_text user "${REFERENCE}"
			(at -0.95 -3.168 90)
			(layer "B.Fab")
			(effects
				(font
					(size 0.7 0.7)
					(thickness 0.15)
				)
				(justify left bottom mirror)
			)
		)
		(fp_text user "Author: Antmicro"
			(at -0.95 -4.169 90)
			(layer "B.Fab")
			(effects
				(font
					(size 0.7 0.7)
					(thickness 0.15)
				)
				(justify left bottom mirror)
			)
		)
		(pad "1" smd roundrect
			(at -0.48 0 270)
			(size 0.59 0.64)
			(layers "B.Cu" "B.Mask" "B.Paste")
			(roundrect_rratio 0.25)
			(net 1089 "Net-(Q1-D)")
			(pintype "passive")
		)
		(pad "2" smd roundrect
			(at 0.48 0 270)
			(size 0.59 0.64)
			(layers "B.Cu" "B.Mask" "B.Paste")
			(roundrect_rratio 0.25)
			(net 2 "+3V3")
			(pintype "passive")
		)
	)
	(footprint "antmicro-footprints:C_0402_1005Metric"
		(layer "B.Cu")
		(at 225.521 77.41 90)
		(descr "Capacitor SMD 0402")
		(tags "capacitor SMD 0402")
		(property "Reference" "C150"
			(at 1.01 -0.321 90)
			(layer "B.SilkS")
			(effects
				(font
					(size 0.7 0.7)
					(thickness 0.15)
				)
				(justify right top mirror)
			)
		)
		(property "Value" "C_47p_0402"
			(at -1.022927 -2.155213 90)
			(layer "B.Fab")
			(effects
				(font
					(size 0.7 0.7)
					(thickness 0.15)
				)
				(justify right top mirror)
			)
		)
		(property "Datasheet" "https://www.kemet.com/en/us/capacitors/product/C0402C470J5GACTU.html"
			(at 0 0 90)
			(layer "B.Fab")
			(hide yes)
			(effects
				(font
					(size 1.27 1.27)
					(thickness 0.15)
				)
				(justify mirror)
			)
		)
		(property "Description" "SMD Multilayer Ceramic Capacitor, 47 pF, 50 V, 0402 [1005 Metric], ± 5%, C0G / NP0, C Series KEMET"
			(at 0 0 90)
			(layer "B.Fab")
			(hide yes)
			(effects
				(font
					(size 1.27 1.27)
					(thickness 0.15)
				)
				(justify mirror)
			)
		)
		(property "MPN" "C0402C470J5GACTU"
			(at 0 0 270)
			(unlocked yes)
			(layer "B.Fab")
			(hide yes)
			(effects
				(font
					(size 1 1)
					(thickness 0.15)
				)
				(justify mirror)
			)
		)
		(property "Manufacturer" "KEMET"
			(at 0 0 270)
			(unlocked yes)
			(layer "B.Fab")
			(hide yes)
			(effects
				(font
					(size 1 1)
					(thickness 0.15)
				)
				(justify mirror)
			)
		)
		(property "License" "Apache-2.0"
			(at 0 0 270)
			(unlocked yes)
			(layer "B.Fab")
			(hide yes)
			(effects
				(font
					(size 1 1)
					(thickness 0.15)
				)
				(justify mirror)
			)
		)
		(property "Author" "Antmicro"
			(at 0 0 270)
			(unlocked yes)
			(layer "B.Fab")
			(hide yes)
			(effects
				(font
					(size 1 1)
					(thickness 0.15)
				)
				(justify mirror)
			)
		)
		(property "Val" "47p"
			(at 0 0 270)
			(unlocked yes)
			(layer "B.Fab")
			(hide yes)
			(effects
				(font
					(size 1 1)
					(thickness 0.15)
				)
				(justify mirror)
			)
		)
		(property "Voltage" ""
			(at 0 0 270)
			(unlocked yes)
			(layer "B.Fab")
			(hide yes)
			(effects
				(font
					(size 1 1)
					(thickness 0.15)
				)
				(justify mirror)
			)
		)
		(property "Dielectric" "C0G"
			(at 0 0 270)
			(unlocked yes)
			(layer "B.Fab")
			(hide yes)
			(effects
				(font
					(size 1 1)
					(thickness 0.15)
				)
				(justify mirror)
			)
		)
		(sheetname "/USB Debug, PD/")
		(sheetfile "usb_debug_pd.kicad_sch")
		(attr smd)
		(fp_rect
			(start -0.925 0.47)
			(end 0.925 -0.47)
			(stroke
				(width 0.05)
				(type default)
			)
			(fill no)
			(layer "B.CrtYd")
		)
		(fp_line
			(start 0.504 -0.248)
			(end -0.494 -0.248)
			(stroke
				(width 0.15)
				(type solid)
			)
			(layer "B.Fab")
		)
		(fp_line
			(start -0.494 -0.248)
			(end -0.494 0.25)
			(stroke
				(width 0.15)
				(type solid)
			)
			(layer "B.Fab")
		)
		(fp_line
			(start 0.504 0.25)
			(end 0.504 -0.248)
			(stroke
				(width 0.15)
				(type solid)
			)
			(layer "B.Fab")
		)
		(fp_line
			(start -0.494 0.25)
			(end 0.504 0.25)
			(stroke
				(width 0.15)
				(type solid)
			)
			(layer "B.Fab")
		)
		(fp_text user "${REFERENCE}"
			(at -0.939 -4.599 90)
			(layer "B.Fab")
			(effects
				(font
					(size 0.7 0.7)
					(thickness 0.15)
				)
				(justify right top mirror)
			)
		)
		(fp_text user "License: Apache-2.0"
			(at -0.939 -5.799 90)
			(layer "B.Fab")
			(effects
				(font
					(size 0.7 0.7)
					(thickness 0.15)
				)
				(justify right top mirror)
			)
		)
		(fp_text user "Author: Antmicro"
			(at -0.939 -3.399 90)
			(layer "B.Fab")
			(effects
				(font
					(size 0.7 0.7)
					(thickness 0.15)
				)
				(justify right top mirror)
			)
		)
		(pad "1" smd roundrect
			(at -0.48 0 90)
			(size 0.59 0.64)
			(layers "B.Cu" "B.Mask" "B.Paste")
			(roundrect_rratio 0.25)
			(net 489 "/USB Debug, PD/USBC0_D_P")
			(pintype "passive")
		)
		(pad "2" smd roundrect
			(at 0.48 0 90)
			(size 0.59 0.64)
			(layers "B.Cu" "B.Mask" "B.Paste")
			(roundrect_rratio 0.25)
			(net 1 "GND")
			(pintype "passive")
		)
	)
	(footprint "antmicro-footprints:TP_SMD_0.75mm"
		(layer "B.Cu")
		(at 138.85 63.85 -90)
		(property "Reference" "TP93"
			(at 0.45 -0.45 90)
			(layer "B.SilkS")
			(effects
				(font
					(size 0.7 0.7)
					(thickness 0.15)
				)
				(justify left bottom mirror)
			)
		)
		(property "Value" "TP_0.75mm_SMD"
			(at 0 -1.2 90)
			(layer "B.Fab")
			(effects
				(font
					(size 0.7 0.7)
					(thickness 0.15)
				)
				(justify left bottom mirror)
			)
		)
		(property "Description" "SMT test point"
			(at 0 0 90)
			(layer "B.Fab")
			(hide yes)
			(effects
				(font
					(size 1.27 1.27)
					(thickness 0.15)
				)
				(justify mirror)
			)
		)
		(property "MPN" ""
			(at 0 0 90)
			(unlocked yes)
			(layer "B.Fab")
			(hide yes)
			(effects
				(font
					(size 1 1)
					(thickness 0.15)
				)
				(justify mirror)
			)
		)
		(property "Manufacturer" ""
			(at 0 0 90)
			(unlocked yes)
			(layer "B.Fab")
			(hide yes)
			(effects
				(font
					(size 1 1)
					(thickness 0.15)
				)
				(justify mirror)
			)
		)
		(property "Author" "Antmicro"
			(at 0 0 90)
			(unlocked yes)
			(layer "B.Fab")
			(hide yes)
			(effects
				(font
					(size 1 1)
					(thickness 0.15)
				)
				(justify mirror)
			)
		)
		(property "License" "Apache-2.0"
			(at 0 0 90)
			(unlocked yes)
			(layer "B.Fab")
			(hide yes)
			(effects
				(font
					(size 1 1)
					(thickness 0.15)
				)
				(justify mirror)
			)
		)
		(sheetname "/Peripherals/")
		(sheetfile "peripherals.kicad_sch")
		(attr exclude_from_pos_files exclude_from_bom)
		(fp_circle
			(center 0 0)
			(end 0.475 0)
			(stroke
				(width 0.05)
				(type default)
			)
			(fill no)
			(layer "B.CrtYd")
		)
		(fp_text user "${REFERENCE}"
			(at -0.4 -2.7 90)
			(layer "B.Fab")
			(effects
				(font
					(size 0.7 0.7)
					(thickness 0.15)
				)
				(justify left bottom mirror)
			)
		)
		(fp_text user "License: Apache-2.0"
			(at -0.4 -5.101 90)
			(layer "B.Fab")
			(effects
				(font
					(size 0.7 0.7)
					(thickness 0.15)
				)
				(justify left bottom mirror)
			)
		)
		(fp_text user "Author: Antmicro"
			(at -0.4 -3.901 90)
			(layer "B.Fab")
			(effects
				(font
					(size 0.7 0.7)
					(thickness 0.15)
				)
				(justify left bottom mirror)
			)
		)
		(pad "1" smd circle
			(at 0 0 270)
			(size 0.75 0.75)
			(layers "B.Cu" "B.Mask")
			(net 838 "/Peripherals/I2C_CONN1_3V3")
			(pinfunction "1")
			(pintype "passive")
		)
	)
)
